# S9S_MB_2U (Grand Teton) — schematic netlist excerpt (pin names and nets, part order shuffled) for the footprints in the layout excerpt that follows; sources: Cadence DE-HDL packaged netlist, KiCad conversion of 03242023_DA0F0TMBIJ0_F0T_Motherboard_J_brd_V01_OCP.brd

R1831  Q_RES  0 5% EMPTY  pkg 0402LF  page 239 : A = JTAG_DBP_BMC_PRDY_N ; B = JTAG_DBP_BMC_PRDY_R_N
H45  HOLE  EMPTY  pkg TH  page 311 : \1\ = GND
PC8  Q_CAP  4.7UF 16V 10% X6S  pkg C0603  page 259 : A = P12V_AUX ; B = GND

(kicad_pcb
	(version 20260206)
	(generator "pcbnew")
	(generator_version "10.0")
	(general
		(thickness 1.6)
		(legacy_teardrops no)
	)
	(paper "A4")
	(title_block
		(title "03242023_DA0F0TMBIJ0_F0T_Motherboard_J_brd_V01_OCP.brd")
		(comment 1 "Grand Teton / footprints 2766-2768 of 6105")
	)
	(layers
		(0 "F.Cu" signal "TOP")
		(4 "In1.Cu" signal "GND")
		(6 "In2.Cu" signal "IN1")
		(8 "In3.Cu" signal "GND1")
		(10 "In4.Cu" signal "IN2")
		(12 "In5.Cu" signal "GND2")
		(14 "In6.Cu" signal "IN3")
		(16 "In7.Cu" signal "GND3")
		(18 "In8.Cu" signal "VCC")
		(20 "In9.Cu" signal "VCC1")
		(22 "In10.Cu" signal "GND4")
		(24 "In11.Cu" signal "IN4")
		(26 "In12.Cu" signal "GND5")
		(28 "In13.Cu" signal "IN5")
		(30 "In14.Cu" signal "GND6")
		(32 "In15.Cu" signal "IN6")
		(34 "In16.Cu" signal "GND7")
		(2 "B.Cu" signal "BOTTOM")
		(9 "F.Adhes" user "F.Adhesive")
		(11 "B.Adhes" user "B.Adhesive")
		(13 "F.Paste" user "Package Geometry/Pastemask Top")
		(15 "B.Paste" user "Package Geometry/Pastemask Bottom")
		(5 "F.SilkS" user "Ref Des/Silkscreen Top")
		(7 "B.SilkS" user "Ref Des/Silkscreen Bottom")
		(1 "F.Mask" user "Board Geometry/Soldermask Top")
		(3 "B.Mask" user "Board Geometry/Soldermask Bottom")
		(17 "Dwgs.User" user "User.Drawings")
		(19 "Cmts.User" user "User.Comments")
		(21 "Eco1.User" user "User.Eco1")
		(23 "Eco2.User" user "User.Eco2")
		(25 "Edge.Cuts" user "Board Geometry/Outline")
		(27 "Margin" user)
		(31 "F.CrtYd" user "Package Geometry/Place Bound Top")
		(29 "B.CrtYd" user "Package Geometry/Place Bound Bottom")
		(35 "F.Fab" user "Ref Des/Assembly Top")
		(33 "B.Fab" user "Ref Des/Assembly Bottom")
	)
	(footprint ""
		(layer "F.Cu")
		(at 329.855068 -353.52482)
		(property "Reference" "H45"
			(at -3.64744 -5.138928 0)
			(unlocked yes)
			(layer "F.SilkS")
			(effects
				(font
					(size 0.7874 0.5842)
					(thickness 0.1524)
				)
				(justify left)
			)
		)
		(property "Value" ""
			(at 0 0 0)
			(layer "F.Fab")
			(effects
				(font
					(size 1.27 1.27)
				)
			)
		)
		(duplicate_pad_numbers_are_jumpers no)
		(pad "1" thru_hole circle
			(at 0 0)
			(size 8.001 8.001)
			(drill 3.2004)
			(layers "*.Cu" "*.Mask")
			(remove_unused_layers no)
			(net "GND")
			(clearance -2.1463)
			(padstack
				(mode front_inner_back)
				(layer "Inner"
					(shape circle)
					(size 5.0038 5.0038)
					(clearance -0.6477)
				)
				(layer "B.Cu"
					(shape circle)
					(size 8.001 8.001)
					(clearance -2.1463)
				)
			)
		)
	)
	(footprint ""
		(layer "F.Cu")
		(at 444.627 -76.164948 90)
		(property "Reference" "PC8"
			(at 0 0 90)
			(layer "F.SilkS")
			(hide yes)
			(effects
				(font
					(size 1.27 1.27)
				)
			)
		)
		(property "Value" ""
			(at 0 0 90)
			(layer "F.Fab")
			(effects
				(font
					(size 1.27 1.27)
				)
			)
		)
		(duplicate_pad_numbers_are_jumpers no)
		(fp_line
			(start 1.2954 -0.5842)
			(end 1.2954 0.5842)
			(stroke
				(width 0.1524)
				(type default)
			)
			(layer "F.SilkS")
		)
		(fp_line
			(start 0 -0.5842)
			(end 0 0.5842)
			(stroke
				(width 0.1524)
				(type default)
			)
			(layer "F.SilkS")
		)
		(fp_line
			(start -1.2954 -0.5842)
			(end 1.2954 -0.5842)
			(stroke
				(width 0.1524)
				(type default)
			)
			(layer "F.SilkS")
		)
		(fp_line
			(start 1.2954 0.5842)
			(end -1.2954 0.5842)
			(stroke
				(width 0.1524)
				(type default)
			)
			(layer "F.SilkS")
		)
		(fp_line
			(start -1.2954 0.5842)
			(end -1.2954 -0.5842)
			(stroke
				(width 0.1524)
				(type default)
			)
			(layer "F.SilkS")
		)
		(fp_line
			(start 0.8636 -0.4572)
			(end 0.8636 -0.4064)
			(stroke
				(width 0.1)
				(type default)
			)
			(layer "F.Fab")
		)
		(fp_line
			(start -0.8636 -0.4572)
			(end 0.8636 -0.4572)
			(stroke
				(width 0.1)
				(type default)
			)
			(layer "F.Fab")
		)
		(fp_line
			(start 1.1938 -0.4064)
			(end 1.1938 0.4064)
			(stroke
				(width 0.1)
				(type default)
			)
			(layer "F.Fab")
		)
		(fp_line
			(start 0.8636 -0.4064)
			(end 1.1938 -0.4064)
			(stroke
				(width 0.1)
				(type default)
			)
			(layer "F.Fab")
		)
		(fp_line
			(start -0.8636 -0.4064)
			(end -0.8636 -0.4572)
			(stroke
				(width 0.1)
				(type default)
			)
			(layer "F.Fab")
		)
		(fp_line
			(start -1.1938 -0.4064)
			(end -0.8636 -0.4064)
			(stroke
				(width 0.1)
				(type default)
			)
			(layer "F.Fab")
		)
		(fp_line
			(start 1.1938 0.4064)
			(end 0.8636 0.4064)
			(stroke
				(width 0.1)
				(type default)
			)
			(layer "F.Fab")
		)
		(fp_line
			(start 0.8636 0.4064)
			(end 0.8636 0.4572)
			(stroke
				(width 0.1)
				(type default)
			)
			(layer "F.Fab")
		)
		(fp_line
			(start -0.8636 0.4064)
			(end -1.1938 0.4064)
			(stroke
				(width 0.1)
				(type default)
			)
			(layer "F.Fab")
		)
		(fp_line
			(start -1.1938 0.4064)
			(end -1.1938 -0.4064)
			(stroke
				(width 0.1)
				(type default)
			)
			(layer "F.Fab")
		)
		(fp_line
			(start 0.8636 0.4572)
			(end -0.8636 0.4572)
			(stroke
				(width 0.1)
				(type default)
			)
			(layer "F.Fab")
		)
		(fp_line
			(start -0.8636 0.4572)
			(end -0.8636 0.4064)
			(stroke
				(width 0.1)
				(type default)
			)
			(layer "F.Fab")
		)
		(pad "1" smd rect
			(at -0.7366 0)
			(size 0.7112 0.8128)
			(layers "F.Cu" "F.Mask" "F.Paste")
			(net "P12V_AUX")
		)
		(pad "2" smd rect
			(at 0.7366 0)
			(size 0.7112 0.8128)
			(layers "F.Cu" "F.Mask" "F.Paste")
			(net "GND")
		)
	)
	(footprint ""
		(layer "F.Cu")
		(at 380.538736 -92.887292 90)
		(property "Reference" "R1831"
			(at 0 0 90)
			(layer "F.SilkS")
			(hide yes)
			(effects
				(font
					(size 1.27 1.27)
				)
			)
		)
		(property "Value" ""
			(at 0 0 90)
			(layer "F.Fab")
			(effects
				(font
					(size 1.27 1.27)
				)
			)
		)
		(duplicate_pad_numbers_are_jumpers no)
		(fp_line
			(start 0.7874 -0.4064)
			(end 0.7874 0.4064)
			(stroke
				(width 0.1524)
				(type default)
			)
			(layer "F.SilkS")
		)
		(fp_line
			(start -0.7874 -0.4064)
			(end 0.7874 -0.4064)
			(stroke
				(width 0.1524)
				(type default)
			)
			(layer "F.SilkS")
		)
		(fp_line
			(start 0.7874 0.4064)
			(end -0.7874 0.4064)
			(stroke
				(width 0.1524)
				(type default)
			)
			(layer "F.SilkS")
		)
		(fp_line
			(start -0.7874 0.4064)
			(end -0.7874 -0.4064)
			(stroke
				(width 0.1524)
				(type default)
			)
			(layer "F.SilkS")
		)
		(fp_line
			(start -0.12065 -0.305054)
			(end -0.12065 -0.2794)
			(stroke
				(width 0.1)
				(type default)
			)
			(layer "F.Fab")
		)
		(fp_line
			(start -0.67945 -0.305054)
			(end -0.12065 -0.305054)
			(stroke
				(width 0.1)
				(type default)
			)
			(layer "F.Fab")
		)
		(fp_line
			(start 0.67945 -0.3048)
			(end 0.67945 0.3048)
			(stroke
				(width 0.1)
				(type default)
			)
			(layer "F.Fab")
		)
		(fp_line
			(start 0.12065 -0.3048)
			(end 0.67945 -0.3048)
			(stroke
				(width 0.1)
				(type default)
			)
			(layer "F.Fab")
		)
		(fp_line
			(start 0.12065 -0.2794)
			(end 0.12065 -0.3048)
			(stroke
				(width 0.1)
				(type default)
			)
			(layer "F.Fab")
		)
		(fp_line
			(start -0.12065 -0.2794)
			(end 0.12065 -0.2794)
			(stroke
				(width 0.1)
				(type default)
			)
			(layer "F.Fab")
		)
		(fp_line
			(start 0.120396 0.2794)
			(end -0.12065 0.2794)
			(stroke
				(width 0.1)
				(type default)
			)
			(layer "F.Fab")
		)
		(fp_line
			(start -0.12065 0.2794)
			(end -0.12065 0.3048)
			(stroke
				(width 0.1)
				(type default)
			)
			(layer "F.Fab")
		)
		(fp_line
			(start 0.67945 0.3048)
			(end 0.120396 0.3048)
			(stroke
				(width 0.1)
				(type default)
			)
			(layer "F.Fab")
		)
		(fp_line
			(start 0.120396 0.3048)
			(end 0.120396 0.2794)
			(stroke
				(width 0.1)
				(type default)
			)
			(layer "F.Fab")
		)
		(fp_line
			(start -0.12065 0.3048)
			(end -0.67945 0.3048)
			(stroke
				(width 0.1)
				(type default)
			)
			(layer "F.Fab")
		)
		(fp_line
			(start -0.67945 0.3048)
			(end -0.67945 -0.305054)
			(stroke
				(width 0.1)
				(type default)
			)
			(layer "F.Fab")
		)
		(pad "1" smd circle
			(at -0.40005 0 90)
			(size 0 0)
			(layers "F.Cu" "F.Mask" "F.Paste")
			(net "JTAG_DBP_BMC_PRDY_N")
		)
		(pad "2" smd circle
			(at 0.40005 0 90)
			(size 0 0)
			(layers "F.Cu" "F.Mask" "F.Paste")
			(net "JTAG_DBP_BMC_PRDY_R_N")
		)
	)
)
